(kicad_pcb
	(version 20241229)
	(generator "pcbnew")
	(generator_version "9.0")
	(general
		(thickness 1.6296)
		(legacy_teardrops no)
	)
	(paper "A3")
	(title_block
		(title "Thunderbolt to 10GbE adapter")
		(date "2026-04-21")
		(rev "1.1.0")
		(company "Antmicro Ltd")
		(comment 1 "www.antmicro.com")
		(comment 9 "footprints 502-505 of 703")
	)
	(layers
		(0 "F.Cu" signal)
		(4 "In1.Cu" signal)
		(6 "In2.Cu" signal)
		(8 "In3.Cu" signal)
		(10 "In4.Cu" signal)
		(12 "In5.Cu" signal)
		(14 "In6.Cu" signal)
		(2 "B.Cu" signal)
		(9 "F.Adhes" user "F.Adhesive")
		(11 "B.Adhes" user "B.Adhesive")
		(13 "F.Paste" user)
		(15 "B.Paste" user)
		(5 "F.SilkS" user "F.Silkscreen")
		(7 "B.SilkS" user "B.Silkscreen")
		(1 "F.Mask" user)
		(3 "B.Mask" user)
		(17 "Dwgs.User" user "User.Drawings")
		(19 "Cmts.User" user "User.Comments")
		(21 "Eco1.User" user "User.Eco1")
		(23 "Eco2.User" user "User.Eco2")
		(25 "Edge.Cuts" user)
		(27 "Margin" user)
		(31 "F.CrtYd" user "F.Courtyard")
		(29 "B.CrtYd" user "B.Courtyard")
		(35 "F.Fab" user)
		(33 "B.Fab" user)
	)
	(footprint "antmicro-footprints:C_0402_1005Metric"
		(layer "B.Cu")
		(at 151.181865 80.260117 180)
		(descr "Capacitor SMD 0402")
		(tags "capacitor SMD 0402")
		(property "Reference" "C256"
			(at -20.368136 -9.464883 0)
			(layer "B.SilkS")
			(effects
				(font
					(size 0.7 0.7)
					(thickness 0.15)
				)
				(justify mirror)
			)
		)
		(property "Value" "C_1u_25V_0402"
			(at -1.022927 -2.155213 0)
			(layer "B.Fab")
			(effects
				(font
					(size 0.7 0.7)
					(thickness 0.15)
				)
				(justify left bottom mirror)
			)
		)
		(property "Datasheet" "https://www.murata.com/products/productdetail?partno=GRM155R61E105KE11%23"
			(at 0 0 0)
			(layer "B.Fab")
			(hide yes)
			(effects
				(font
					(size 1.27 1.27)
					(thickness 0.15)
				)
				(justify mirror)
			)
		)
		(property "Description" "SMD Multilayer Ceramic Capacitor, 1 µF, 25 V, 0402 [1005 Metric], ± 10%, X5R, GRM Series"
			(at 0 0 0)
			(layer "B.Fab")
			(hide yes)
			(effects
				(font
					(size 1.27 1.27)
					(thickness 0.15)
				)
				(justify mirror)
			)
		)
		(property "MPN" "GRM155R61E105KE11J"
			(at 0 0 180)
			(unlocked yes)
			(layer "B.Fab")
			(hide yes)
			(effects
				(font
					(size 1 1)
					(thickness 0.15)
				)
				(justify mirror)
			)
		)
		(property "Manufacturer" "Murata"
			(at 0 0 180)
			(unlocked yes)
			(layer "B.Fab")
			(hide yes)
			(effects
				(font
					(size 1 1)
					(thickness 0.15)
				)
				(justify mirror)
			)
		)
		(property "License" "Apache-2.0"
			(at 0 0 180)
			(unlocked yes)
			(layer "B.Fab")
			(hide yes)
			(effects
				(font
					(size 1 1)
					(thickness 0.15)
				)
				(justify mirror)
			)
		)
		(property "Author" "Antmicro"
			(at 0 0 180)
			(unlocked yes)
			(layer "B.Fab")
			(hide yes)
			(effects
				(font
					(size 1 1)
					(thickness 0.15)
				)
				(justify mirror)
			)
		)
		(property "Val" "1u"
			(at 0 0 180)
			(unlocked yes)
			(layer "B.Fab")
			(hide yes)
			(effects
				(font
					(size 1 1)
					(thickness 0.15)
				)
				(justify mirror)
			)
		)
		(property "Voltage" "25V"
			(at 0 0 180)
			(unlocked yes)
			(layer "B.Fab")
			(hide yes)
			(effects
				(font
					(size 1 1)
					(thickness 0.15)
				)
				(justify mirror)
			)
		)
		(property "Dielectric" "X5R"
			(at 0 0 180)
			(unlocked yes)
			(layer "B.Fab")
			(hide yes)
			(effects
				(font
					(size 1 1)
					(thickness 0.15)
				)
				(justify mirror)
			)
		)
		(sheetname "/X710-AT2 power/")
		(sheetfile "x710-at2-power.kicad_sch")
		(attr smd)
		(fp_rect
			(start -0.925 0.47)
			(end 0.925 -0.47)
			(stroke
				(width 0.05)
				(type default)
			)
			(fill no)
			(layer "B.CrtYd")
		)
		(fp_line
			(start 0.504 0.25)
			(end 0.504 -0.248)
			(stroke
				(width 0.15)
				(type solid)
			)
			(layer "B.Fab")
		)
		(fp_line
			(start 0.504 -0.248)
			(end -0.494 -0.248)
			(stroke
				(width 0.15)
				(type solid)
			)
			(layer "B.Fab")
		)
		(fp_line
			(start -0.494 0.25)
			(end 0.504 0.25)
			(stroke
				(width 0.15)
				(type solid)
			)
			(layer "B.Fab")
		)
		(fp_line
			(start -0.494 -0.248)
			(end -0.494 0.25)
			(stroke
				(width 0.15)
				(type solid)
			)
			(layer "B.Fab")
		)
		(fp_text user "Author: Antmicro"
			(at -0.939 -3.399 0)
			(layer "B.Fab")
			(effects
				(font
					(size 0.7 0.7)
					(thickness 0.15)
				)
				(justify left bottom mirror)
			)
		)
		(fp_text user "${REFERENCE}"
			(at -0.939 -4.599 0)
			(layer "B.Fab")
			(effects
				(font
					(size 0.7 0.7)
					(thickness 0.15)
				)
				(justify left bottom mirror)
			)
		)
		(fp_text user "License: Apache-2.0"
			(at -0.939 -5.799 0)
			(layer "B.Fab")
			(effects
				(font
					(size 0.7 0.7)
					(thickness 0.15)
				)
				(justify left bottom mirror)
			)
		)
		(pad "1" smd roundrect
			(at -0.48 0 180)
			(size 0.59 0.64)
			(layers "B.Cu" "B.Mask" "B.Paste")
			(roundrect_rratio 0.25)
			(net 23 "GND")
			(pintype "passive")
		)
		(pad "2" smd roundrect
			(at 0.48 0 180)
			(size 0.59 0.64)
			(layers "B.Cu" "B.Mask" "B.Paste")
			(roundrect_rratio 0.25)
			(net 9 "VCCD")
			(pintype "passive")
		)
	)
	(footprint "antmicro-footprints:C_0402_1005Metric"
		(layer "B.Cu")
		(at 156.111865 86.125116 180)
		(descr "Capacitor SMD 0402")
		(tags "capacitor SMD 0402")
		(property "Reference" "C190"
			(at -19.873134 -9.464883 0)
			(layer "B.SilkS")
			(effects
				(font
					(size 0.7 0.7)
					(thickness 0.15)
				)
				(justify mirror)
			)
		)
		(property "Value" "C_1u_25V_0402"
			(at -1.022927 -2.155213 0)
			(layer "B.Fab")
			(effects
				(font
					(size 0.7 0.7)
					(thickness 0.15)
				)
				(justify left bottom mirror)
			)
		)
		(property "Datasheet" "https://www.murata.com/products/productdetail?partno=GRM155R61E105KE11%23"
			(at 0 0 0)
			(layer "B.Fab")
			(hide yes)
			(effects
				(font
					(size 1.27 1.27)
					(thickness 0.15)
				)
				(justify mirror)
			)
		)
		(property "Description" "SMD Multilayer Ceramic Capacitor, 1 µF, 25 V, 0402 [1005 Metric], ± 10%, X5R, GRM Series"
			(at 0 0 0)
			(layer "B.Fab")
			(hide yes)
			(effects
				(font
					(size 1.27 1.27)
					(thickness 0.15)
				)
				(justify mirror)
			)
		)
		(property "MPN" "GRM155R61E105KE11J"
			(at 0 0 180)
			(unlocked yes)
			(layer "B.Fab")
			(hide yes)
			(effects
				(font
					(size 1 1)
					(thickness 0.15)
				)
				(justify mirror)
			)
		)
		(property "Manufacturer" "Murata"
			(at 0 0 180)
			(unlocked yes)
			(layer "B.Fab")
			(hide yes)
			(effects
				(font
					(size 1 1)
					(thickness 0.15)
				)
				(justify mirror)
			)
		)
		(property "License" "Apache-2.0"
			(at 0 0 180)
			(unlocked yes)
			(layer "B.Fab")
			(hide yes)
			(effects
				(font
					(size 1 1)
					(thickness 0.15)
				)
				(justify mirror)
			)
		)
		(property "Author" "Antmicro"
			(at 0 0 180)
			(unlocked yes)
			(layer "B.Fab")
			(hide yes)
			(effects
				(font
					(size 1 1)
					(thickness 0.15)
				)
				(justify mirror)
			)
		)
		(property "Val" "1u"
			(at 0 0 180)
			(unlocked yes)
			(layer "B.Fab")
			(hide yes)
			(effects
				(font
					(size 1 1)
					(thickness 0.15)
				)
				(justify mirror)
			)
		)
		(property "Voltage" "25V"
			(at 0 0 180)
			(unlocked yes)
			(layer "B.Fab")
			(hide yes)
			(effects
				(font
					(size 1 1)
					(thickness 0.15)
				)
				(justify mirror)
			)
		)
		(property "Dielectric" "X5R"
			(at 0 0 180)
			(unlocked yes)
			(layer "B.Fab")
			(hide yes)
			(effects
				(font
					(size 1 1)
					(thickness 0.15)
				)
				(justify mirror)
			)
		)
		(sheetname "/X710-AT2 power/")
		(sheetfile "x710-at2-power.kicad_sch")
		(attr smd)
		(fp_rect
			(start -0.925 0.47)
			(end 0.925 -0.47)
			(stroke
				(width 0.05)
				(type default)
			)
			(fill no)
			(layer "B.CrtYd")
		)
		(fp_line
			(start 0.504 0.25)
			(end 0.504 -0.248)
			(stroke
				(width 0.15)
				(type solid)
			)
			(layer "B.Fab")
		)
		(fp_line
			(start 0.504 -0.248)
			(end -0.494 -0.248)
			(stroke
				(width 0.15)
				(type solid)
			)
			(layer "B.Fab")
		)
		(fp_line
			(start -0.494 0.25)
			(end 0.504 0.25)
			(stroke
				(width 0.15)
				(type solid)
			)
			(layer "B.Fab")
		)
		(fp_line
			(start -0.494 -0.248)
			(end -0.494 0.25)
			(stroke
				(width 0.15)
				(type solid)
			)
			(layer "B.Fab")
		)
		(fp_text user "${REFERENCE}"
			(at -0.939 -4.599 0)
			(layer "B.Fab")
			(effects
				(font
					(size 0.7 0.7)
					(thickness 0.15)
				)
				(justify left bottom mirror)
			)
		)
		(fp_text user "Author: Antmicro"
			(at -0.939 -3.399 0)
			(layer "B.Fab")
			(effects
				(font
					(size 0.7 0.7)
					(thickness 0.15)
				)
				(justify left bottom mirror)
			)
		)
		(fp_text user "License: Apache-2.0"
			(at -0.939 -5.799 0)
			(layer "B.Fab")
			(effects
				(font
					(size 0.7 0.7)
					(thickness 0.15)
				)
				(justify left bottom mirror)
			)
		)
		(pad "1" smd roundrect
			(at -0.48 0 180)
			(size 0.59 0.64)
			(layers "B.Cu" "B.Mask" "B.Paste")
			(roundrect_rratio 0.25)
			(net 23 "GND")
			(pintype "passive")
		)
		(pad "2" smd roundrect
			(at 0.48 0 180)
			(size 0.59 0.64)
			(layers "B.Cu" "B.Mask" "B.Paste")
			(roundrect_rratio 0.25)
			(net 6 "DVDD")
			(pintype "passive")
		)
	)
	(footprint "antmicro-footprints:C_0402_1005Metric"
		(layer "B.Cu")
		(at 157.511866 87.605117 -90)
		(descr "Capacitor SMD 0402")
		(tags "capacitor SMD 0402")
		(property "Reference" "C183"
			(at 9.794883 -20.393133 90)
			(layer "B.SilkS")
			(effects
				(font
					(size 0.7 0.7)
					(thickness 0.15)
				)
				(justify mirror)
			)
		)
		(property "Value" "C_1u_25V_0402"
			(at -1.022927 -2.155213 90)
			(layer "B.Fab")
			(effects
				(font
					(size 0.7 0.7)
					(thickness 0.15)
				)
				(justify left bottom mirror)
			)
		)
		(property "Datasheet" "https://www.murata.com/products/productdetail?partno=GRM155R61E105KE11%23"
			(at 0 0 90)
			(layer "B.Fab")
			(hide yes)
			(effects
				(font
					(size 1.27 1.27)
					(thickness 0.15)
				)
				(justify mirror)
			)
		)
		(property "Description" "SMD Multilayer Ceramic Capacitor, 1 µF, 25 V, 0402 [1005 Metric], ± 10%, X5R, GRM Series"
			(at 0 0 90)
			(layer "B.Fab")
			(hide yes)
			(effects
				(font
					(size 1.27 1.27)
					(thickness 0.15)
				)
				(justify mirror)
			)
		)
		(property "MPN" "GRM155R61E105KE11J"
			(at 0 0 270)
			(unlocked yes)
			(layer "B.Fab")
			(hide yes)
			(effects
				(font
					(size 1 1)
					(thickness 0.15)
				)
				(justify mirror)
			)
		)
		(property "Manufacturer" "Murata"
			(at 0 0 270)
			(unlocked yes)
			(layer "B.Fab")
			(hide yes)
			(effects
				(font
					(size 1 1)
					(thickness 0.15)
				)
				(justify mirror)
			)
		)
		(property "License" "Apache-2.0"
			(at 0 0 270)
			(unlocked yes)
			(layer "B.Fab")
			(hide yes)
			(effects
				(font
					(size 1 1)
					(thickness 0.15)
				)
				(justify mirror)
			)
		)
		(property "Author" "Antmicro"
			(at 0 0 270)
			(unlocked yes)
			(layer "B.Fab")
			(hide yes)
			(effects
				(font
					(size 1 1)
					(thickness 0.15)
				)
				(justify mirror)
			)
		)
		(property "Val" "1u"
			(at 0 0 270)
			(unlocked yes)
			(layer "B.Fab")
			(hide yes)
			(effects
				(font
					(size 1 1)
					(thickness 0.15)
				)
				(justify mirror)
			)
		)
		(property "Voltage" "25V"
			(at 0 0 270)
			(unlocked yes)
			(layer "B.Fab")
			(hide yes)
			(effects
				(font
					(size 1 1)
					(thickness 0.15)
				)
				(justify mirror)
			)
		)
		(property "Dielectric" "X5R"
			(at 0 0 270)
			(unlocked yes)
			(layer "B.Fab")
			(hide yes)
			(effects
				(font
					(size 1 1)
					(thickness 0.15)
				)
				(justify mirror)
			)
		)
		(sheetname "/X710-AT2 power/")
		(sheetfile "x710-at2-power.kicad_sch")
		(attr smd)
		(fp_rect
			(start -0.925 0.47)
			(end 0.925 -0.47)
			(stroke
				(width 0.05)
				(type default)
			)
			(fill no)
			(layer "B.CrtYd")
		)
		(fp_line
			(start -0.494 0.25)
			(end 0.504 0.25)
			(stroke
				(width 0.15)
				(type solid)
			)
			(layer "B.Fab")
		)
		(fp_line
			(start 0.504 0.25)
			(end 0.504 -0.248)
			(stroke
				(width 0.15)
				(type solid)
			)
			(layer "B.Fab")
		)
		(fp_line
			(start -0.494 -0.248)
			(end -0.494 0.25)
			(stroke
				(width 0.15)
				(type solid)
			)
			(layer "B.Fab")
		)
		(fp_line
			(start 0.504 -0.248)
			(end -0.494 -0.248)
			(stroke
				(width 0.15)
				(type solid)
			)
			(layer "B.Fab")
		)
		(fp_text user "Author: Antmicro"
			(at -0.939 -3.399 90)
			(layer "B.Fab")
			(effects
				(font
					(size 0.7 0.7)
					(thickness 0.15)
				)
				(justify left bottom mirror)
			)
		)
		(fp_text user "License: Apache-2.0"
			(at -0.939 -5.799 90)
			(layer "B.Fab")
			(effects
				(font
					(size 0.7 0.7)
					(thickness 0.15)
				)
				(justify left bottom mirror)
			)
		)
		(fp_text user "${REFERENCE}"
			(at -0.939 -4.599 90)
			(layer "B.Fab")
			(effects
				(font
					(size 0.7 0.7)
					(thickness 0.15)
				)
				(justify left bottom mirror)
			)
		)
		(pad "1" smd roundrect
			(at -0.48 0 270)
			(size 0.59 0.64)
			(layers "B.Cu" "B.Mask" "B.Paste")
			(roundrect_rratio 0.25)
			(net 23 "GND")
			(pintype "passive")
		)
		(pad "2" smd roundrect
			(at 0.48 0 270)
			(size 0.59 0.64)
			(layers "B.Cu" "B.Mask" "B.Paste")
			(roundrect_rratio 0.25)
			(net 10 "AVDDH")
			(pintype "passive")
		)
	)
	(footprint "antmicro-footprints:C_0402_1005Metric"
		(layer "B.Cu")
		(at 151.181866 77.260117 180)
		(descr "Capacitor SMD 0402")
		(tags "capacitor SMD 0402")
		(property "Reference" "C227"
			(at -20.368136 -9.464883 0)
			(layer "B.SilkS")
			(effects
				(font
					(size 0.7 0.7)
					(thickness 0.15)
				)
				(justify mirror)
			)
		)
		(property "Value" "C_1u_25V_0402"
			(at -1.022927 -2.155213 0)
			(layer "B.Fab")
			(effects
				(font
					(size 0.7 0.7)
					(thickness 0.15)
				)
				(justify left bottom mirror)
			)
		)
		(property "Datasheet" "https://www.murata.com/products/productdetail?partno=GRM155R61E105KE11%23"
			(at 0 0 0)
			(layer "B.Fab")
			(hide yes)
			(effects
				(font
					(size 1.27 1.27)
					(thickness 0.15)
				)
				(justify mirror)
			)
		)
		(property "Description" "SMD Multilayer Ceramic Capacitor, 1 µF, 25 V, 0402 [1005 Metric], ± 10%, X5R, GRM Series"
			(at 0 0 0)
			(layer "B.Fab")
			(hide yes)
			(effects
				(font
					(size 1.27 1.27)
					(thickness 0.15)
				)
				(justify mirror)
			)
		)
		(property "MPN" "GRM155R61E105KE11J"
			(at 0 0 180)
			(unlocked yes)
			(layer "B.Fab")
			(hide yes)
			(effects
				(font
					(size 1 1)
					(thickness 0.15)
				)
				(justify mirror)
			)
		)
		(property "Manufacturer" "Murata"
			(at 0 0 180)
			(unlocked yes)
			(layer "B.Fab")
			(hide yes)
			(effects
				(font
					(size 1 1)
					(thickness 0.15)
				)
				(justify mirror)
			)
		)
		(property "License" "Apache-2.0"
			(at 0 0 180)
			(unlocked yes)
			(layer "B.Fab")
			(hide yes)
			(effects
				(font
					(size 1 1)
					(thickness 0.15)
				)
				(justify mirror)
			)
		)
		(property "Author" "Antmicro"
			(at 0 0 180)
			(unlocked yes)
			(layer "B.Fab")
			(hide yes)
			(effects
				(font
					(size 1 1)
					(thickness 0.15)
				)
				(justify mirror)
			)
		)
		(property "Val" "1u"
			(at 0 0 180)
			(unlocked yes)
			(layer "B.Fab")
			(hide yes)
			(effects
				(font
					(size 1 1)
					(thickness 0.15)
				)
				(justify mirror)
			)
		)
		(property "Voltage" "25V"
			(at 0 0 180)
			(unlocked yes)
			(layer "B.Fab")
			(hide yes)
			(effects
				(font
					(size 1 1)
					(thickness 0.15)
				)
				(justify mirror)
			)
		)
		(property "Dielectric" "X5R"
			(at 0 0 180)
			(unlocked yes)
			(layer "B.Fab")
			(hide yes)
			(effects
				(font
					(size 1 1)
					(thickness 0.15)
				)
				(justify mirror)
			)
		)
		(sheetname "/X710-AT2 power/")
		(sheetfile "x710-at2-power.kicad_sch")
		(attr smd)
		(fp_rect
			(start -0.925 0.47)
			(end 0.925 -0.47)
			(stroke
				(width 0.05)
				(type default)
			)
			(fill no)
			(layer "B.CrtYd")
		)
		(fp_line
			(start 0.504 0.25)
			(end 0.504 -0.248)
			(stroke
				(width 0.15)
				(type solid)
			)
			(layer "B.Fab")
		)
		(fp_line
			(start 0.504 -0.248)
			(end -0.494 -0.248)
			(stroke
				(width 0.15)
				(type solid)
			)
			(layer "B.Fab")
		)
		(fp_line
			(start -0.494 0.25)
			(end 0.504 0.25)
			(stroke
				(width 0.15)
				(type solid)
			)
			(layer "B.Fab")
		)
		(fp_line
			(start -0.494 -0.248)
			(end -0.494 0.25)
			(stroke
				(width 0.15)
				(type solid)
			)
			(layer "B.Fab")
		)
		(fp_text user "${REFERENCE}"
			(at -0.939 -4.599 0)
			(layer "B.Fab")
			(effects
				(font
					(size 0.7 0.7)
					(thickness 0.15)
				)
				(justify left bottom mirror)
			)
		)
		(fp_text user "License: Apache-2.0"
			(at -0.939 -5.799 0)
			(layer "B.Fab")
			(effects
				(font
					(size 0.7 0.7)
					(thickness 0.15)
				)
				(justify left bottom mirror)
			)
		)
		(fp_text user "Author: Antmicro"
			(at -0.939 -3.399 0)
			(layer "B.Fab")
			(effects
				(font
					(size 0.7 0.7)
					(thickness 0.15)
				)
				(justify left bottom mirror)
			)
		)
		(pad "1" smd roundrect
			(at -0.48 0 180)
			(size 0.59 0.64)
			(layers "B.Cu" "B.Mask" "B.Paste")
			(roundrect_rratio 0.25)
			(net 23 "GND")
			(pintype "passive")
		)
		(pad "2" smd roundrect
			(at 0.48 0 180)
			(size 0.59 0.64)
			(layers "B.Cu" "B.Mask" "B.Paste")
			(roundrect_rratio 0.25)
			(net 1 "VCCA")
			(pintype "passive")
		)
	)
)
